(kicad_pcb
	(version 20240108)
	(generator "pcbnew")
	(generator_version "8.0")
	(general
		(thickness 1.62)
		(legacy_teardrops no)
	)
	(paper "A4")
	(title_block
		(title "Jetson Orin Baseboard")
		(date "2025-03-12")
		(rev "1.3.4")
		(company "Antmicro Ltd")
		(comment 1 "www.antmicro.com")
		(comment 9 "footprints 245-246 of 677")
	)
	(layers
		(0 "F.Cu" signal)
		(1 "In1.Cu" signal)
		(2 "In2.Cu" signal)
		(3 "In3.Cu" signal)
		(4 "In4.Cu" jumper)
		(5 "In5.Cu" signal)
		(6 "In6.Cu" signal)
		(31 "B.Cu" signal)
		(32 "B.Adhes" user "B.Adhesive")
		(33 "F.Adhes" user "F.Adhesive")
		(34 "B.Paste" user)
		(35 "F.Paste" user)
		(36 "B.SilkS" user "B.Silkscreen")
		(37 "F.SilkS" user "F.Silkscreen")
		(38 "B.Mask" user)
		(39 "F.Mask" user)
		(40 "Dwgs.User" user "User.Drawings")
		(41 "Cmts.User" user "User.Comments")
		(42 "Eco1.User" user "User.Eco1")
		(43 "Eco2.User" user "User.Eco2")
		(44 "Edge.Cuts" user)
		(45 "Margin" user)
		(46 "B.CrtYd" user "B.Courtyard")
		(47 "F.CrtYd" user "F.Courtyard")
		(48 "B.Fab" user)
		(49 "F.Fab" user)
	)
	(footprint "antmicro-footprints:LED_0603_1608Metric_G"
		(layer "F.Cu")
		(at 134.7 127.2 -90)
		(descr "LED SMD 0603 Green")
		(tags "LED SMD 0603 Green")
		(property "Reference" "D26"
			(at -1.2 0.5 90)
			(layer "F.SilkS")
			(effects
				(font
					(size 0.7 0.7)
					(thickness 0.15)
				)
				(justify right bottom)
			)
		)
		(property "Value" "LED_G_0603_LTST-C190GKT"
			(at -0.001 1.599 90)
			(layer "F.Fab")
			(effects
				(font
					(size 0.7 0.7)
					(thickness 0.15)
				)
				(justify right bottom)
			)
		)
		(property "Footprint" "antmicro-footprints:LED_0603_1608Metric_G"
			(at 0 0 -90)
			(layer "F.Fab")
			(hide yes)
			(effects
				(font
					(size 1.27 1.27)
					(thickness 0.15)
				)
			)
		)
		(property "Datasheet" "https://media.digikey.com/pdf/Data%20Sheets/Lite-On%20PDFs/LTST-C190GKT.pdf"
			(at 0 0 -90)
			(layer "F.Fab")
			(hide yes)
			(effects
				(font
					(size 1.27 1.27)
					(thickness 0.15)
				)
			)
		)
		(property "Author" "Antmicro"
			(at 7.5 261.9 0)
			(layer "F.Fab")
			(hide yes)
			(effects
				(font
					(size 1 1)
					(thickness 0.15)
				)
			)
		)
		(property "Color" "Green"
			(at 7.5 261.9 0)
			(layer "F.Fab")
			(hide yes)
			(effects
				(font
					(size 1 1)
					(thickness 0.15)
				)
			)
		)
		(property "License" "Apache-2.0"
			(at 7.5 261.9 0)
			(layer "F.Fab")
			(hide yes)
			(effects
				(font
					(size 1 1)
					(thickness 0.15)
				)
			)
		)
		(property "MPN" "LTST-C190GKT"
			(at 7.5 261.9 0)
			(layer "F.Fab")
			(hide yes)
			(effects
				(font
					(size 1 1)
					(thickness 0.15)
				)
			)
		)
		(property "Manufacturer" "Lite-On"
			(at 7.5 261.9 0)
			(layer "F.Fab")
			(hide yes)
			(effects
				(font
					(size 1 1)
					(thickness 0.15)
				)
			)
		)
		(sheetname "Peripherals")
		(sheetfile "peripherals.kicad_sch")
		(attr smd)
		(fp_line
			(start 0.22 0.35)
			(end -0.22 0.35)
			(stroke
				(width 0.15)
				(type solid)
			)
			(layer "F.SilkS")
		)
		(fp_line
			(start -0.094672 0.201008)
			(end -0.094672 -0.198992)
			(stroke
				(width 0.1)
				(type solid)
			)
			(layer "F.SilkS")
		)
		(fp_line
			(start 0.105328 0.201008)
			(end -0.094672 0.001008)
			(stroke
				(width 0.1)
				(type solid)
			)
			(layer "F.SilkS")
		)
		(fp_line
			(start 0.105328 0.201008)
			(end 0.105328 -0.198992)
			(stroke
				(width 0.1)
				(type solid)
			)
			(layer "F.SilkS")
		)
		(fp_line
			(start -0.094672 0.001008)
			(end -0.24 0.001008)
			(stroke
				(width 0.1)
				(type solid)
			)
			(layer "F.SilkS")
		)
		(fp_line
			(start -0.094672 0.001008)
			(end 0.105328 -0.198992)
			(stroke
				(width 0.1)
				(type solid)
			)
			(layer "F.SilkS")
		)
		(fp_line
			(start 0.105328 0.001008)
			(end 0.24 0.001)
			(stroke
				(width 0.1)
				(type solid)
			)
			(layer "F.SilkS")
		)
		(fp_line
			(start -1.18 -0.319)
			(end -1.18 0.321)
			(stroke
				(width 0.15)
				(type solid)
			)
			(layer "F.SilkS")
		)
		(fp_line
			(start 0.22 -0.35)
			(end -0.22 -0.35)
			(stroke
				(width 0.15)
				(type solid)
			)
			(layer "F.SilkS")
		)
		(fp_rect
			(start 1.25 0.65)
			(end -1.25 -0.65)
			(stroke
				(width 0.05)
				(type solid)
			)
			(fill none)
			(layer "F.CrtYd")
		)
		(fp_line
			(start -0.199 0.2)
			(end -0.199 0.1)
			(stroke
				(width 0.15)
				(type solid)
			)
			(layer "F.Fab")
		)
		(fp_line
			(start 0.201 0.2)
			(end 0.201 0)
			(stroke
				(width 0.15)
				(type solid)
			)
			(layer "F.Fab")
		)
		(fp_line
			(start -0.199 0)
			(end -0.597 0)
			(stroke
				(width 0.15)
				(type solid)
			)
			(layer "F.Fab")
		)
		(fp_line
			(start -0.101 0)
			(end 0.201 0.2)
			(stroke
				(width 0.15)
				(type solid)
			)
			(layer "F.Fab")
		)
		(fp_line
			(start 0.201 0)
			(end 0.201 -0.202)
			(stroke
				(width 0.15)
				(type solid)
			)
			(layer "F.Fab")
		)
		(fp_line
			(start 0.599 0)
			(end 0.201 0)
			(stroke
				(width 0.15)
				(type solid)
			)
			(layer "F.Fab")
		)
		(fp_line
			(start -0.199 -0.202)
			(end -0.199 0.1)
			(stroke
				(width 0.15)
				(type solid)
			)
			(layer "F.Fab")
		)
		(fp_line
			(start 0.201 -0.202)
			(end -0.101 0)
			(stroke
				(width 0.15)
				(type solid)
			)
			(layer "F.Fab")
		)
		(fp_rect
			(start 0.848 0.4)
			(end -0.85 -0.402)
			(stroke
				(width 0.15)
				(type solid)
			)
			(fill none)
			(layer "F.Fab")
		)
		(fp_text user "License: Apache-2.0"
			(at -1.4224 3.599 90)
			(layer "F.Fab")
			(hide yes)
			(effects
				(font
					(size 0.7 0.7)
					(thickness 0.15)
				)
				(justify right bottom)
			)
		)
		(fp_text user "Author: Antmicro"
			(at -1.4224 4.799 90)
			(layer "F.Fab")
			(hide yes)
			(effects
				(font
					(size 0.7 0.7)
					(thickness 0.15)
				)
				(justify right bottom)
			)
		)
		(fp_text user "${REFERENCE}"
			(at -1.4224 5.999 90)
			(layer "F.Fab")
			(hide yes)
			(effects
				(font
					(size 0.7 0.7)
					(thickness 0.15)
				)
				(justify right bottom)
			)
		)
		(pad "1" smd roundrect
			(at -0.7 0 90)
			(size 0.8 1)
			(layers "F.Cu" "F.Paste" "F.Mask")
			(roundrect_rratio 0.2)
			(net 164 "Net-(D26-C)")
			(pinfunction "C")
			(pintype "passive")
		)
		(pad "2" smd roundrect
			(at 0.7 0 90)
			(size 0.8 1)
			(layers "F.Cu" "F.Paste" "F.Mask")
			(roundrect_rratio 0.2)
			(net 180 "Net-(D26-A)")
			(pinfunction "A")
			(pintype "passive")
		)
	)
	(footprint "antmicro-footprints:R_Array_4x0201_Panasonic_EXB18V"
		(layer "F.Cu")
		(at 107.87 98.24 -90)
		(property "Reference" "R51"
			(at -0.84 -0.43 90)
			(layer "F.SilkS")
			(effects
				(font
					(size 0.7 0.7)
					(thickness 0.15)
				)
				(justify left bottom)
			)
		)
		(property "Value" "R_4x0R_0201_array"
			(at -1.1 1.8 -90)
			(layer "F.Fab")
			(effects
				(font
					(size 0.7 0.7)
					(thickness 0.15)
				)
				(justify left bottom)
			)
		)
		(property "Footprint" "antmicro-footprints:R_Array_4x0201_Panasonic_EXB18V"
			(at 0 0 -90)
			(layer "F.Fab")
			(hide yes)
			(effects
				(font
					(size 1.27 1.27)
					(thickness 0.15)
				)
			)
		)
		(property "Datasheet" "http://industrial.panasonic.com/cdbs/www-data/pdf/AOC0000/AOC0000C14.pdf"
			(at 0 0 -90)
			(layer "F.Fab")
			(hide yes)
			(effects
				(font
					(size 1.27 1.27)
					(thickness 0.15)
				)
			)
		)
		(property "Author" "Antmicro"
			(at 9.63 206.11 0)
			(layer "F.Fab")
			(hide yes)
			(effects
				(font
					(size 1 1)
					(thickness 0.15)
				)
			)
		)
		(property "License" "Apache-2.0"
			(at 9.63 206.11 0)
			(layer "F.Fab")
			(hide yes)
			(effects
				(font
					(size 1 1)
					(thickness 0.15)
				)
			)
		)
		(property "MPN" "EXB-18VR000X"
			(at 9.63 206.11 0)
			(layer "F.Fab")
			(hide yes)
			(effects
				(font
					(size 1 1)
					(thickness 0.15)
				)
			)
		)
		(property "Manufacturer" "Panasonic"
			(at 9.63 206.11 0)
			(layer "F.Fab")
			(hide yes)
			(effects
				(font
					(size 1 1)
					(thickness 0.15)
				)
			)
		)
		(property "Val" "4x0R_0201"
			(at 9.63 206.11 0)
			(layer "F.Fab")
			(hide yes)
			(effects
				(font
					(size 1 1)
					(thickness 0.15)
				)
			)
		)
		(sheetname "CSI")
		(sheetfile "csi.kicad_sch")
		(attr smd)
		(fp_line
			(start -0.8 -0.45)
			(end -0.8 0.45)
			(stroke
				(width 0.12)
				(type solid)
			)
			(layer "F.SilkS")
		)
		(fp_line
			(start 0.8 -0.45)
			(end 0.8 0.45)
			(stroke
				(width 0.12)
				(type solid)
			)
			(layer "F.SilkS")
		)
		(fp_rect
			(start -0.898 -0.66)
			(end 0.898 0.65)
			(stroke
				(width 0.05)
				(type solid)
			)
			(fill none)
			(layer "F.CrtYd")
		)
		(fp_text user "License: Apache-2.0"
			(at -1.051 6 -90)
			(layer "F.Fab")
			(hide yes)
			(effects
				(font
					(size 0.7 0.7)
					(thickness 0.15)
				)
				(justify left bottom)
			)
		)
		(fp_text user "Author: Antmicro"
			(at -1.051 4.599 -90)
			(layer "F.Fab")
			(hide yes)
			(effects
				(font
					(size 0.7 0.7)
					(thickness 0.15)
				)
				(justify left bottom)
			)
		)
		(fp_text user "${REFERENCE}"
			(at -1.051 3.2 -90)
			(layer "F.Fab")
			(hide yes)
			(effects
				(font
					(size 0.7 0.7)
					(thickness 0.15)
				)
				(justify left bottom)
			)
		)
		(pad "1" smd roundrect
			(at -0.6 0.298 270)
			(size 0.2 0.4)
			(layers "F.Cu" "F.Paste" "F.Mask")
			(roundrect_rratio 0.25)
			(net 331 "/CSI/SDA_CAM2")
			(pinfunction "R1.1")
			(pintype "passive")
		)
		(pad "2" smd roundrect
			(at -0.202 0.298 270)
			(size 0.2 0.4)
			(layers "F.Cu" "F.Paste" "F.Mask")
			(roundrect_rratio 0.25)
			(net 333 "/CSI/SCL_CAM2")
			(pinfunction "R2.1")
			(pintype "passive")
		)
		(pad "3" smd roundrect
			(at 0.2 0.298 270)
			(size 0.2 0.4)
			(layers "F.Cu" "F.Paste" "F.Mask")
			(roundrect_rratio 0.25)
			(net 336 "/CSI/SDA_CAM3")
			(pinfunction "R3.1")
			(pintype "passive")
		)
		(pad "4" smd roundrect
			(at 0.598 0.298 270)
			(size 0.2 0.4)
			(layers "F.Cu" "F.Paste" "F.Mask")
			(roundrect_rratio 0.25)
			(net 337 "/CSI/SCL_CAM3")
			(pinfunction "R4.1")
			(pintype "passive")
		)
		(pad "5" smd roundrect
			(at 0.598 -0.3 270)
			(size 0.2 0.4)
			(layers "F.Cu" "F.Paste" "F.Mask")
			(roundrect_rratio 0.25)
			(net 603 "Net-(R51-R4.2)")
			(pinfunction "R4.2")
			(pintype "passive")
		)
		(pad "6" smd roundrect
			(at 0.2 -0.3 270)
			(size 0.2 0.4)
			(layers "F.Cu" "F.Paste" "F.Mask")
			(roundrect_rratio 0.25)
			(net 602 "Net-(R51-R3.2)")
			(pinfunction "R3.2")
			(pintype "passive")
		)
		(pad "7" smd roundrect
			(at -0.202 -0.3 270)
			(size 0.2 0.4)
			(layers "F.Cu" "F.Paste" "F.Mask")
			(roundrect_rratio 0.25)
			(net 577 "Net-(R51-R2.2)")
			(pinfunction "R2.2")
			(pintype "passive")
		)
		(pad "8" smd roundrect
			(at -0.6 -0.3 270)
			(size 0.2 0.4)
			(layers "F.Cu" "F.Paste" "F.Mask")
			(roundrect_rratio 0.25)
			(net 575 "Net-(R51-R1.2)")
			(pinfunction "R1.2")
			(pintype "passive")
		)
	)
)
